(kicad_pcb
	(version 20260206)
	(generator "pcbnew")
	(generator_version "10.0")
	(general
		(thickness 1.6)
		(legacy_teardrops no)
	)
	(paper "A4")
	(title_block
		(title "Wiwynn_Tioga_Pass_MB.brd")
		(comment 1 "Tioga Pass / footprints 3797-3803 of 4770")
	)
	(layers
		(0 "F.Cu" signal "TOP")
		(4 "In1.Cu" signal "L2GND")
		(6 "In2.Cu" signal "L3")
		(8 "In3.Cu" signal "L4GND")
		(10 "In4.Cu" signal "L5")
		(12 "In5.Cu" signal "L6GND")
		(14 "In6.Cu" signal "L7VCC")
		(16 "In7.Cu" signal "L8VCC")
		(18 "In8.Cu" signal "L9GND")
		(20 "In9.Cu" signal "L10")
		(22 "In10.Cu" signal "L11GND")
		(24 "In11.Cu" signal "L12")
		(26 "In12.Cu" signal "L13GND")
		(2 "B.Cu" signal "BOTTOM")
		(9 "F.Adhes" user "F.Adhesive")
		(11 "B.Adhes" user "B.Adhesive")
		(13 "F.Paste" user "Package Geometry/Pastemask Top")
		(15 "B.Paste" user "Package Geometry/Pastemask Bottom")
		(5 "F.SilkS" user "Ref Des/Silkscreen Top")
		(7 "B.SilkS" user "Ref Des/Silkscreen Bottom")
		(1 "F.Mask" user "Board Geometry/Soldermask Top")
		(3 "B.Mask" user "Board Geometry/Soldermask Bottom")
		(17 "Dwgs.User" user "User.Drawings")
		(19 "Cmts.User" user "User.Comments")
		(21 "Eco1.User" user "User.Eco1")
		(23 "Eco2.User" user "User.Eco2")
		(25 "Edge.Cuts" user "Board Geometry/Outline")
		(27 "Margin" user)
		(31 "F.CrtYd" user "Package Geometry/Place Bound Top")
		(29 "B.CrtYd" user "Package Geometry/Place Bound Bottom")
		(35 "F.Fab" user "Ref Des/Assembly Top")
		(33 "B.Fab" user "Ref Des/Assembly Bottom")
	)
	(footprint ""
		(layer "B.Cu")
		(at 384.0734 -156.569664 -90)
		(property "Reference" "R3L14"
			(at 0 0 90)
			(layer "B.SilkS")
			(hide yes)
			(effects
				(font
					(size 1.27 1.27)
				)
				(justify mirror)
			)
		)
		(property "Value" ""
			(at 0 0 90)
			(layer "B.Fab")
			(effects
				(font
					(size 1.27 1.27)
				)
				(justify mirror)
			)
		)
		(duplicate_pad_numbers_are_jumpers no)
		(fp_poly
			(pts
				(xy 0.2794 -0.1016) (xy -0.2794 -0.1016) (xy -0.2794 0.9906) (xy 0.2794 0.9906)
			)
			(stroke
				(width 0)
				(type default)
			)
			(fill no)
			(layer "B.CrtYd")
		)
		(fp_line
			(start -0.2794 0.9906)
			(end -0.2794 -0.1016)
			(stroke
				(width 0.1)
				(type default)
			)
			(layer "B.Fab")
		)
		(fp_line
			(start 0.2794 0.9906)
			(end -0.2794 0.9906)
			(stroke
				(width 0.1)
				(type default)
			)
			(layer "B.Fab")
		)
		(fp_line
			(start -0.2794 -0.1016)
			(end 0.2794 -0.1016)
			(stroke
				(width 0.1)
				(type default)
			)
			(layer "B.Fab")
		)
		(fp_line
			(start 0.2794 -0.1016)
			(end 0.2794 0.9906)
			(stroke
				(width 0.1)
				(type default)
			)
			(layer "B.Fab")
		)
		(pad "1" smd rect
			(at 0 0 90)
			(size 0.508 0.508)
			(layers "B.Cu" "B.Mask" "B.Paste")
			(net "VR_P1V05_PCH_STBY_OCSET")
		)
		(pad "2" smd rect
			(at 0 0.889 90)
			(size 0.508 0.508)
			(layers "B.Cu" "B.Mask" "B.Paste")
			(net "GND")
		)
		(zone
			(layer "B.Cu")
			(hatch none 0.5)
			(connect_pads
				(clearance 0)
			)
			(min_thickness 0.25)
			(keepout
				(tracks not_allowed)
				(vias allowed)
				(pads allowed)
				(copperpour not_allowed)
				(footprints allowed)
			)
			(placement
				(enabled no)
				(sheetname "")
			)
			(fill
				(thermal_gap 0.5)
				(thermal_bridge_width 0.5)
				(island_removal_mode 0)
			)
			(polygon
				(pts
					(xy 383.4384 -156.315664) (xy 383.4384 -156.823664) (xy 383.8194 -156.823664) (xy 383.8194 -156.315664)
				)
			)
		)
		(zone
			(layer "B.Cu")
			(hatch none 0.5)
			(connect_pads
				(clearance 0)
			)
			(min_thickness 0.25)
			(keepout
				(tracks allowed)
				(vias not_allowed)
				(pads allowed)
				(copperpour not_allowed)
				(footprints allowed)
			)
			(placement
				(enabled no)
				(sheetname "")
			)
			(fill
				(thermal_gap 0.5)
				(thermal_bridge_width 0.5)
				(island_removal_mode 0)
			)
			(polygon
				(pts
					(xy 383.8194 -156.315664) (xy 383.8194 -156.823664) (xy 383.4384 -156.823664) (xy 383.4384 -156.315664)
				)
			)
		)
	)
	(footprint ""
		(layer "B.Cu")
		(at 482.131116 -144.771872 -90)
		(property "Reference" "R6W5"
			(at 0.8382 -0.67818 270)
			(unlocked yes)
			(layer "B.SilkS")
			(effects
				(font
					(size 0.4064 0.254)
					(thickness 0.1524)
				)
				(justify left mirror)
			)
		)
		(property "Value" ""
			(at 0 0 90)
			(layer "B.Fab")
			(effects
				(font
					(size 1.27 1.27)
				)
				(justify mirror)
			)
		)
		(duplicate_pad_numbers_are_jumpers no)
		(fp_poly
			(pts
				(xy 0.2794 -0.1016) (xy -0.2794 -0.1016) (xy -0.2794 0.9906) (xy 0.2794 0.9906)
			)
			(stroke
				(width 0)
				(type default)
			)
			(fill no)
			(layer "B.CrtYd")
		)
		(fp_line
			(start -0.2794 0.9906)
			(end -0.2794 -0.1016)
			(stroke
				(width 0.1)
				(type default)
			)
			(layer "B.Fab")
		)
		(fp_line
			(start 0.2794 0.9906)
			(end -0.2794 0.9906)
			(stroke
				(width 0.1)
				(type default)
			)
			(layer "B.Fab")
		)
		(fp_line
			(start -0.2794 -0.1016)
			(end 0.2794 -0.1016)
			(stroke
				(width 0.1)
				(type default)
			)
			(layer "B.Fab")
		)
		(fp_line
			(start 0.2794 -0.1016)
			(end 0.2794 0.9906)
			(stroke
				(width 0.1)
				(type default)
			)
			(layer "B.Fab")
		)
		(pad "1" smd rect
			(at 0 0 90)
			(size 0.508 0.508)
			(layers "B.Cu" "B.Mask" "B.Paste")
			(net "P3V3_STBY")
		)
		(pad "2" smd rect
			(at 0 0.889 90)
			(size 0.508 0.508)
			(layers "B.Cu" "B.Mask" "B.Paste")
			(net "PCA9555_A1")
		)
		(zone
			(layer "B.Cu")
			(hatch none 0.5)
			(connect_pads
				(clearance 0)
			)
			(min_thickness 0.25)
			(keepout
				(tracks not_allowed)
				(vias allowed)
				(pads allowed)
				(copperpour not_allowed)
				(footprints allowed)
			)
			(placement
				(enabled no)
				(sheetname "")
			)
			(fill
				(thermal_gap 0.5)
				(thermal_bridge_width 0.5)
				(island_removal_mode 0)
			)
			(polygon
				(pts
					(xy 481.496116 -144.517872) (xy 481.496116 -145.025872) (xy 481.877116 -145.025872) (xy 481.877116 -144.517872)
				)
			)
		)
		(zone
			(layer "B.Cu")
			(hatch none 0.5)
			(connect_pads
				(clearance 0)
			)
			(min_thickness 0.25)
			(keepout
				(tracks allowed)
				(vias not_allowed)
				(pads allowed)
				(copperpour not_allowed)
				(footprints allowed)
			)
			(placement
				(enabled no)
				(sheetname "")
			)
			(fill
				(thermal_gap 0.5)
				(thermal_bridge_width 0.5)
				(island_removal_mode 0)
			)
			(polygon
				(pts
					(xy 481.877116 -144.517872) (xy 481.877116 -145.025872) (xy 481.496116 -145.025872) (xy 481.496116 -144.517872)
				)
			)
		)
	)
	(footprint ""
		(layer "B.Cu")
		(at -0.127 -132.334)
		(property "Reference" "R9M5"
			(at 0 0 0)
			(layer "B.SilkS")
			(hide yes)
			(effects
				(font
					(size 1.27 1.27)
				)
				(justify mirror)
			)
		)
		(property "Value" ""
			(at 0 0 0)
			(layer "B.Fab")
			(effects
				(font
					(size 1.27 1.27)
				)
				(justify mirror)
			)
		)
		(duplicate_pad_numbers_are_jumpers no)
		(fp_poly
			(pts
				(xy 0.2794 -0.1016) (xy -0.2794 -0.1016) (xy -0.2794 0.9906) (xy 0.2794 0.9906)
			)
			(stroke
				(width 0)
				(type default)
			)
			(fill no)
			(layer "B.CrtYd")
		)
		(fp_line
			(start -0.2794 -0.1016)
			(end 0.2794 -0.1016)
			(stroke
				(width 0.1)
				(type default)
			)
			(layer "B.Fab")
		)
		(fp_line
			(start -0.2794 0.9906)
			(end -0.2794 -0.1016)
			(stroke
				(width 0.1)
				(type default)
			)
			(layer "B.Fab")
		)
		(fp_line
			(start 0.2794 -0.1016)
			(end 0.2794 0.9906)
			(stroke
				(width 0.1)
				(type default)
			)
			(layer "B.Fab")
		)
		(fp_line
			(start 0.2794 0.9906)
			(end -0.2794 0.9906)
			(stroke
				(width 0.1)
				(type default)
			)
			(layer "B.Fab")
		)
		(pad "1" smd rect
			(at 0 0 180)
			(size 0.508 0.508)
			(layers "B.Cu" "B.Mask" "B.Paste")
			(net "P3V3_STBY")
		)
		(pad "2" smd rect
			(at 0 0.889 180)
			(size 0.508 0.508)
			(layers "B.Cu" "B.Mask" "B.Paste")
			(net "VR_PVDDQ_KLM_VREN")
		)
		(zone
			(layer "B.Cu")
			(hatch none 0.5)
			(connect_pads
				(clearance 0)
			)
			(min_thickness 0.25)
			(keepout
				(tracks allowed)
				(vias not_allowed)
				(pads allowed)
				(copperpour not_allowed)
				(footprints allowed)
			)
			(placement
				(enabled no)
				(sheetname "")
			)
			(fill
				(thermal_gap 0.5)
				(thermal_bridge_width 0.5)
				(island_removal_mode 0)
			)
			(polygon
				(pts
					(xy 0.127 -132.08) (xy -0.381 -132.08) (xy -0.381 -131.699) (xy 0.127 -131.699)
				)
			)
		)
		(zone
			(layer "B.Cu")
			(hatch none 0.5)
			(connect_pads
				(clearance 0)
			)
			(min_thickness 0.25)
			(keepout
				(tracks not_allowed)
				(vias allowed)
				(pads allowed)
				(copperpour not_allowed)
				(footprints allowed)
			)
			(placement
				(enabled no)
				(sheetname "")
			)
			(fill
				(thermal_gap 0.5)
				(thermal_bridge_width 0.5)
				(island_removal_mode 0)
			)
			(polygon
				(pts
					(xy 0.127 -131.699) (xy -0.381 -131.699) (xy -0.381 -132.08) (xy 0.127 -132.08)
				)
			)
		)
	)
	(footprint ""
		(layer "B.Cu")
		(at -1.3335 -145.8214 90)
		(property "Reference" "CT10"
			(at 0.8382 -0.84963 90)
			(unlocked yes)
			(layer "B.SilkS")
			(effects
				(font
					(size 0.7874 0.5842)
					(thickness 0.1524)
				)
				(justify left mirror)
			)
		)
		(property "Value" ""
			(at 0 0 90)
			(layer "B.Fab")
			(effects
				(font
					(size 1.27 1.27)
				)
				(justify mirror)
			)
		)
		(duplicate_pad_numbers_are_jumpers no)
		(fp_poly
			(pts
				(xy -0.3048 -0.1016) (xy -0.3048 0.9906) (xy 0.3048 0.9906) (xy 0.3048 -0.1016)
			)
			(stroke
				(width 0)
				(type default)
			)
			(fill no)
			(layer "B.CrtYd")
		)
		(fp_line
			(start 0.3048 -0.1016)
			(end 0.3048 0.9906)
			(stroke
				(width 0.1)
				(type default)
			)
			(layer "B.Fab")
		)
		(fp_line
			(start -0.3048 -0.1016)
			(end 0.3048 -0.1016)
			(stroke
				(width 0.1)
				(type default)
			)
			(layer "B.Fab")
		)
		(fp_line
			(start 0.3048 0.9906)
			(end -0.3048 0.9906)
			(stroke
				(width 0.1)
				(type default)
			)
			(layer "B.Fab")
		)
		(fp_line
			(start -0.3048 0.9906)
			(end -0.3048 -0.1016)
			(stroke
				(width 0.1)
				(type default)
			)
			(layer "B.Fab")
		)
		(pad "1" smd rect
			(at 0 0 270)
			(size 0.508 0.508)
			(layers "B.Cu" "B.Mask" "B.Paste")
			(net "A_TSENSE_PVDDQ_KLM")
		)
		(pad "2" smd rect
			(at 0 0.889 270)
			(size 0.508 0.508)
			(layers "B.Cu" "B.Mask" "B.Paste")
			(net "GND")
		)
		(zone
			(layer "B.Cu")
			(hatch none 0.5)
			(connect_pads
				(clearance 0)
			)
			(min_thickness 0.25)
			(keepout
				(tracks allowed)
				(vias not_allowed)
				(pads allowed)
				(copperpour not_allowed)
				(footprints allowed)
			)
			(placement
				(enabled no)
				(sheetname "")
			)
			(fill
				(thermal_gap 0.5)
				(thermal_bridge_width 0.5)
				(island_removal_mode 0)
			)
			(polygon
				(pts
					(xy -1.0795 -146.0754) (xy -1.0795 -145.5674) (xy -0.6985 -145.5674) (xy -0.6985 -146.0754)
				)
			)
		)
		(zone
			(layer "B.Cu")
			(hatch none 0.5)
			(connect_pads
				(clearance 0)
			)
			(min_thickness 0.25)
			(keepout
				(tracks not_allowed)
				(vias allowed)
				(pads allowed)
				(copperpour not_allowed)
				(footprints allowed)
			)
			(placement
				(enabled no)
				(sheetname "")
			)
			(fill
				(thermal_gap 0.5)
				(thermal_bridge_width 0.5)
				(island_removal_mode 0)
			)
			(polygon
				(pts
					(xy -0.6985 -146.0754) (xy -0.6985 -145.5674) (xy -1.0795 -145.5674) (xy -1.0795 -146.0754)
				)
			)
		)
	)
	(footprint ""
		(layer "B.Cu")
		(at 382.397 -2.448814)
		(property "Reference" "C8W6"
			(at 0.8382 -0.67818 0)
			(unlocked yes)
			(layer "B.SilkS")
			(effects
				(font
					(size 0.4064 0.254)
					(thickness 0.1524)
				)
				(justify left mirror)
			)
		)
		(property "Value" ""
			(at 0 0 0)
			(layer "B.Fab")
			(effects
				(font
					(size 1.27 1.27)
				)
				(justify mirror)
			)
		)
		(duplicate_pad_numbers_are_jumpers no)
		(fp_poly
			(pts
				(xy -0.3048 -0.1016) (xy -0.3048 0.9906) (xy 0.3048 0.9906) (xy 0.3048 -0.1016)
			)
			(stroke
				(width 0)
				(type default)
			)
			(fill no)
			(layer "B.CrtYd")
		)
		(fp_line
			(start -0.3048 -0.1016)
			(end 0.3048 -0.1016)
			(stroke
				(width 0.1)
				(type default)
			)
			(layer "B.Fab")
		)
		(fp_line
			(start -0.3048 0.9906)
			(end -0.3048 -0.1016)
			(stroke
				(width 0.1)
				(type default)
			)
			(layer "B.Fab")
		)
		(fp_line
			(start 0.3048 -0.1016)
			(end 0.3048 0.9906)
			(stroke
				(width 0.1)
				(type default)
			)
			(layer "B.Fab")
		)
		(fp_line
			(start 0.3048 0.9906)
			(end -0.3048 0.9906)
			(stroke
				(width 0.1)
				(type default)
			)
			(layer "B.Fab")
		)
		(pad "1" smd rect
			(at 0 0 180)
			(size 0.508 0.508)
			(layers "B.Cu" "B.Mask" "B.Paste")
			(net "P3V3_STBY")
		)
		(pad "2" smd rect
			(at 0 0.889 180)
			(size 0.508 0.508)
			(layers "B.Cu" "B.Mask" "B.Paste")
			(net "GND")
		)
		(zone
			(layer "B.Cu")
			(hatch none 0.5)
			(connect_pads
				(clearance 0)
			)
			(min_thickness 0.25)
			(keepout
				(tracks allowed)
				(vias not_allowed)
				(pads allowed)
				(copperpour not_allowed)
				(footprints allowed)
			)
			(placement
				(enabled no)
				(sheetname "")
			)
			(fill
				(thermal_gap 0.5)
				(thermal_bridge_width 0.5)
				(island_removal_mode 0)
			)
			(polygon
				(pts
					(xy 382.651 -2.194814) (xy 382.143 -2.194814) (xy 382.143 -1.813814) (xy 382.651 -1.813814)
				)
			)
		)
		(zone
			(layer "B.Cu")
			(hatch none 0.5)
			(connect_pads
				(clearance 0)
			)
			(min_thickness 0.25)
			(keepout
				(tracks not_allowed)
				(vias allowed)
				(pads allowed)
				(copperpour not_allowed)
				(footprints allowed)
			)
			(placement
				(enabled no)
				(sheetname "")
			)
			(fill
				(thermal_gap 0.5)
				(thermal_bridge_width 0.5)
				(island_removal_mode 0)
			)
			(polygon
				(pts
					(xy 382.651 -1.813814) (xy 382.143 -1.813814) (xy 382.143 -2.194814) (xy 382.651 -2.194814)
				)
			)
		)
	)
	(footprint ""
		(layer "B.Cu")
		(at 370.156994 -93.915992 -90)
		(property "Reference" "R3P7"
			(at 0 0 90)
			(layer "B.SilkS")
			(hide yes)
			(effects
				(font
					(size 1.27 1.27)
				)
				(justify mirror)
			)
		)
		(property "Value" ""
			(at 0 0 90)
			(layer "B.Fab")
			(effects
				(font
					(size 1.27 1.27)
				)
				(justify mirror)
			)
		)
		(duplicate_pad_numbers_are_jumpers no)
		(fp_poly
			(pts
				(xy 0.2794 -0.1016) (xy -0.2794 -0.1016) (xy -0.2794 0.9906) (xy 0.2794 0.9906)
			)
			(stroke
				(width 0)
				(type default)
			)
			(fill no)
			(layer "B.CrtYd")
		)
		(fp_line
			(start -0.2794 0.9906)
			(end -0.2794 -0.1016)
			(stroke
				(width 0.1)
				(type default)
			)
			(layer "B.Fab")
		)
		(fp_line
			(start 0.2794 0.9906)
			(end -0.2794 0.9906)
			(stroke
				(width 0.1)
				(type default)
			)
			(layer "B.Fab")
		)
		(fp_line
			(start -0.2794 -0.1016)
			(end 0.2794 -0.1016)
			(stroke
				(width 0.1)
				(type default)
			)
			(layer "B.Fab")
		)
		(fp_line
			(start 0.2794 -0.1016)
			(end 0.2794 0.9906)
			(stroke
				(width 0.1)
				(type default)
			)
			(layer "B.Fab")
		)
		(pad "1" smd rect
			(at 0 0 90)
			(size 0.508 0.508)
			(layers "B.Cu" "B.Mask" "B.Paste")
			(net "P1V05_PCH_STBY")
		)
		(pad "2" smd rect
			(at 0 0.889 90)
			(size 0.508 0.508)
			(layers "B.Cu" "B.Mask" "B.Paste")
			(net "FM_PRSNT_2_1_N")
		)
		(zone
			(layer "B.Cu")
			(hatch none 0.5)
			(connect_pads
				(clearance 0)
			)
			(min_thickness 0.25)
			(keepout
				(tracks not_allowed)
				(vias allowed)
				(pads allowed)
				(copperpour not_allowed)
				(footprints allowed)
			)
			(placement
				(enabled no)
				(sheetname "")
			)
			(fill
				(thermal_gap 0.5)
				(thermal_bridge_width 0.5)
				(island_removal_mode 0)
			)
			(polygon
				(pts
					(xy 369.521994 -93.661992) (xy 369.521994 -94.169992) (xy 369.902994 -94.169992) (xy 369.902994 -93.661992)
				)
			)
		)
		(zone
			(layer "B.Cu")
			(hatch none 0.5)
			(connect_pads
				(clearance 0)
			)
			(min_thickness 0.25)
			(keepout
				(tracks allowed)
				(vias not_allowed)
				(pads allowed)
				(copperpour not_allowed)
				(footprints allowed)
			)
			(placement
				(enabled no)
				(sheetname "")
			)
			(fill
				(thermal_gap 0.5)
				(thermal_bridge_width 0.5)
				(island_removal_mode 0)
			)
			(polygon
				(pts
					(xy 369.902994 -93.661992) (xy 369.902994 -94.169992) (xy 369.521994 -94.169992) (xy 369.521994 -93.661992)
				)
			)
		)
	)
	(footprint ""
		(layer "B.Cu")
		(at 445.5922 -155.8544 180)
		(property "Reference" "U25W18"
			(at 0.14986 2.621788 180)
			(unlocked yes)
			(layer "B.SilkS")
			(effects
				(font
					(size 1.27 0.964946)
					(thickness 0.000001)
				)
				(justify left mirror)
			)
		)
		(property "Value" ""
			(at 0 0 0)
			(layer "B.Fab")
			(effects
				(font
					(size 1.27 1.27)
				)
				(justify mirror)
			)
		)
		(duplicate_pad_numbers_are_jumpers no)
		(fp_circle
			(center 0.4699 -0.8382)
			(end 0.3429 -0.8382)
			(stroke
				(width 0.254)
				(type default)
			)
			(fill no)
			(layer "B.SilkS")
		)
		(fp_poly
			(pts
				(xy -0.21463 -0.450088) (xy -1.56337 -0.450088) (xy -1.56337 1.75006) (xy -0.21463 1.75006)
			)
			(stroke
				(width 0)
				(type default)
			)
			(fill no)
			(layer "B.CrtYd")
		)
		(fp_line
			(start -0.21463 1.75006)
			(end -0.21463 -0.450088)
			(stroke
				(width 0.1)
				(type default)
			)
			(layer "B.Fab")
		)
		(fp_line
			(start -0.21463 -0.450088)
			(end -1.56337 -0.450088)
			(stroke
				(width 0.1)
				(type default)
			)
			(layer "B.Fab")
		)
		(fp_line
			(start -1.56337 1.75006)
			(end -0.21463 1.75006)
			(stroke
				(width 0.1)
				(type default)
			)
			(layer "B.Fab")
		)
		(fp_line
			(start -1.56337 -0.450088)
			(end -1.56337 1.75006)
			(stroke
				(width 0.1)
				(type default)
			)
			(layer "B.Fab")
		)
		(fp_circle
			(center 0.4699 -0.8382)
			(end 0.3429 -0.8382)
			(stroke
				(width 0.254)
				(type default)
			)
			(fill no)
			(layer "B.Fab")
		)
		(pad "1" smd rect
			(at 0 0)
			(size 1.016 0.381)
			(layers "B.Cu" "B.Mask" "B.Paste")
			(net "XDP_PRESENT_N")
		)
		(pad "2" smd rect
			(at 0 0.649986)
			(size 1.016 0.381)
			(layers "B.Cu" "B.Mask" "B.Paste")
			(net "BMC_JTAG_SEL")
		)
		(pad "3" smd rect
			(at 0 1.299972)
			(size 1.016 0.381)
			(layers "B.Cu" "B.Mask" "B.Paste")
			(net "GND")
		)
		(pad "4" smd rect
			(at -1.778 1.299972)
			(size 1.016 0.381)
			(layers "B.Cu" "B.Mask" "B.Paste")
			(net "BMC_JTAG_SEL_BUF")
		)
		(pad "5" smd rect
			(at -1.778 0)
			(size 1.016 0.381)
			(layers "B.Cu" "B.Mask" "B.Paste")
			(net "P3V3_STBY")
		)
	)
)
